# S9S_MB_2U (Grand Teton) — schematic netlist excerpt (pin names and nets, part order shuffled) for the footprints in the layout excerpt that follows; sources: Cadence DE-HDL packaged netlist, KiCad conversion of 03242023_DA0F0TMBIJ0_F0T_Motherboard_J_brd_V01_OCP.brd

R4273  Q_RES  1K 1% EMPTY  pkg 0402LF  page 169 : A = P3V3_AUX ; B = FM_USB3_1_FGB
R4109  Q_RES  10K 1% CHIP  pkg 0402LF  page 184 : A = PD_GPP_I_15 ; B = GND

(kicad_pcb
	(version 20260206)
	(generator "pcbnew")
	(generator_version "10.0")
	(general
		(thickness 1.6)
		(legacy_teardrops no)
	)
	(paper "A4")
	(title_block
		(title "03242023_DA0F0TMBIJ0_F0T_Motherboard_J_brd_V01_OCP.brd")
		(comment 1 "Grand Teton / footprints 5831-5832 of 6105")
	)
	(layers
		(0 "F.Cu" signal "TOP")
		(4 "In1.Cu" signal "GND")
		(6 "In2.Cu" signal "IN1")
		(8 "In3.Cu" signal "GND1")
		(10 "In4.Cu" signal "IN2")
		(12 "In5.Cu" signal "GND2")
		(14 "In6.Cu" signal "IN3")
		(16 "In7.Cu" signal "GND3")
		(18 "In8.Cu" signal "VCC")
		(20 "In9.Cu" signal "VCC1")
		(22 "In10.Cu" signal "GND4")
		(24 "In11.Cu" signal "IN4")
		(26 "In12.Cu" signal "GND5")
		(28 "In13.Cu" signal "IN5")
		(30 "In14.Cu" signal "GND6")
		(32 "In15.Cu" signal "IN6")
		(34 "In16.Cu" signal "GND7")
		(2 "B.Cu" signal "BOTTOM")
		(9 "F.Adhes" user "F.Adhesive")
		(11 "B.Adhes" user "B.Adhesive")
		(13 "F.Paste" user "Package Geometry/Pastemask Top")
		(15 "B.Paste" user "Package Geometry/Pastemask Bottom")
		(5 "F.SilkS" user "Ref Des/Silkscreen Top")
		(7 "B.SilkS" user "Ref Des/Silkscreen Bottom")
		(1 "F.Mask" user "Board Geometry/Soldermask Top")
		(3 "B.Mask" user "Board Geometry/Soldermask Bottom")
		(17 "Dwgs.User" user "User.Drawings")
		(19 "Cmts.User" user "User.Comments")
		(21 "Eco1.User" user "User.Eco1")
		(23 "Eco2.User" user "User.Eco2")
		(25 "Edge.Cuts" user "Board Geometry/Outline")
		(27 "Margin" user)
		(31 "F.CrtYd" user "Package Geometry/Place Bound Top")
		(29 "B.CrtYd" user "Package Geometry/Place Bound Bottom")
		(35 "F.Fab" user "Ref Des/Assembly Top")
		(33 "B.Fab" user "Ref Des/Assembly Bottom")
	)
	(footprint ""
		(layer "B.Cu")
		(at 128.85928 -31.542228 90)
		(property "Reference" "R4273"
			(at 0 0 90)
			(layer "B.SilkS")
			(hide yes)
			(effects
				(font
					(size 1.27 1.27)
				)
				(justify mirror)
			)
		)
		(property "Value" ""
			(at 0 0 90)
			(layer "B.Fab")
			(effects
				(font
					(size 1.27 1.27)
				)
				(justify mirror)
			)
		)
		(duplicate_pad_numbers_are_jumpers no)
		(fp_line
			(start 0.7874 -0.4064)
			(end -0.7874 -0.4064)
			(stroke
				(width 0.1524)
				(type default)
			)
			(layer "B.SilkS")
		)
		(fp_line
			(start -0.7874 -0.4064)
			(end -0.7874 0.4064)
			(stroke
				(width 0.1524)
				(type default)
			)
			(layer "B.SilkS")
		)
		(fp_line
			(start 0.7874 0.4064)
			(end 0.7874 -0.4064)
			(stroke
				(width 0.1524)
				(type default)
			)
			(layer "B.SilkS")
		)
		(fp_line
			(start -0.7874 0.4064)
			(end 0.7874 0.4064)
			(stroke
				(width 0.1524)
				(type default)
			)
			(layer "B.SilkS")
		)
		(fp_line
			(start 0.67945 -0.305054)
			(end 0.12065 -0.305054)
			(stroke
				(width 0.1)
				(type default)
			)
			(layer "B.Fab")
		)
		(fp_line
			(start 0.12065 -0.305054)
			(end 0.12065 -0.2794)
			(stroke
				(width 0.1)
				(type default)
			)
			(layer "B.Fab")
		)
		(fp_line
			(start -0.12065 -0.3048)
			(end -0.67945 -0.3048)
			(stroke
				(width 0.1)
				(type default)
			)
			(layer "B.Fab")
		)
		(fp_line
			(start -0.67945 -0.3048)
			(end -0.67945 0.3048)
			(stroke
				(width 0.1)
				(type default)
			)
			(layer "B.Fab")
		)
		(fp_line
			(start 0.12065 -0.2794)
			(end -0.12065 -0.2794)
			(stroke
				(width 0.1)
				(type default)
			)
			(layer "B.Fab")
		)
		(fp_line
			(start -0.12065 -0.2794)
			(end -0.12065 -0.3048)
			(stroke
				(width 0.1)
				(type default)
			)
			(layer "B.Fab")
		)
		(fp_line
			(start 0.12065 0.2794)
			(end 0.12065 0.3048)
			(stroke
				(width 0.1)
				(type default)
			)
			(layer "B.Fab")
		)
		(fp_line
			(start -0.120396 0.2794)
			(end 0.12065 0.2794)
			(stroke
				(width 0.1)
				(type default)
			)
			(layer "B.Fab")
		)
		(fp_line
			(start 0.67945 0.3048)
			(end 0.67945 -0.305054)
			(stroke
				(width 0.1)
				(type default)
			)
			(layer "B.Fab")
		)
		(fp_line
			(start 0.12065 0.3048)
			(end 0.67945 0.3048)
			(stroke
				(width 0.1)
				(type default)
			)
			(layer "B.Fab")
		)
		(fp_line
			(start -0.120396 0.3048)
			(end -0.120396 0.2794)
			(stroke
				(width 0.1)
				(type default)
			)
			(layer "B.Fab")
		)
		(fp_line
			(start -0.67945 0.3048)
			(end -0.120396 0.3048)
			(stroke
				(width 0.1)
				(type default)
			)
			(layer "B.Fab")
		)
		(pad "1" smd circle
			(at 0.40005 0 270)
			(size 0 0)
			(layers "B.Cu" "B.Mask" "B.Paste")
			(net "P3V3_AUX")
		)
		(pad "2" smd circle
			(at -0.40005 0 270)
			(size 0 0)
			(layers "B.Cu" "B.Mask" "B.Paste")
			(net "FM_USB3_1_FGB")
		)
	)
	(footprint ""
		(layer "B.Cu")
		(at 315.110622 -54.219348)
		(property "Reference" "R4109"
			(at 0 0 0)
			(layer "B.SilkS")
			(hide yes)
			(effects
				(font
					(size 1.27 1.27)
				)
				(justify mirror)
			)
		)
		(property "Value" ""
			(at 0 0 0)
			(layer "B.Fab")
			(effects
				(font
					(size 1.27 1.27)
				)
				(justify mirror)
			)
		)
		(duplicate_pad_numbers_are_jumpers no)
		(fp_line
			(start -0.7874 -0.4064)
			(end -0.7874 0.4064)
			(stroke
				(width 0.1524)
				(type default)
			)
			(layer "B.SilkS")
		)
		(fp_line
			(start -0.7874 0.4064)
			(end 0.7874 0.4064)
			(stroke
				(width 0.1524)
				(type default)
			)
			(layer "B.SilkS")
		)
		(fp_line
			(start 0.7874 -0.4064)
			(end -0.7874 -0.4064)
			(stroke
				(width 0.1524)
				(type default)
			)
			(layer "B.SilkS")
		)
		(fp_line
			(start 0.7874 0.4064)
			(end 0.7874 -0.4064)
			(stroke
				(width 0.1524)
				(type default)
			)
			(layer "B.SilkS")
		)
		(fp_line
			(start -0.67945 -0.3048)
			(end -0.67945 0.3048)
			(stroke
				(width 0.1)
				(type default)
			)
			(layer "B.Fab")
		)
		(fp_line
			(start -0.67945 0.3048)
			(end -0.120396 0.3048)
			(stroke
				(width 0.1)
				(type default)
			)
			(layer "B.Fab")
		)
		(fp_line
			(start -0.12065 -0.3048)
			(end -0.67945 -0.3048)
			(stroke
				(width 0.1)
				(type default)
			)
			(layer "B.Fab")
		)
		(fp_line
			(start -0.12065 -0.2794)
			(end -0.12065 -0.3048)
			(stroke
				(width 0.1)
				(type default)
			)
			(layer "B.Fab")
		)
		(fp_line
			(start -0.120396 0.2794)
			(end 0.12065 0.2794)
			(stroke
				(width 0.1)
				(type default)
			)
			(layer "B.Fab")
		)
		(fp_line
			(start -0.120396 0.3048)
			(end -0.120396 0.2794)
			(stroke
				(width 0.1)
				(type default)
			)
			(layer "B.Fab")
		)
		(fp_line
			(start 0.12065 -0.305054)
			(end 0.12065 -0.2794)
			(stroke
				(width 0.1)
				(type default)
			)
			(layer "B.Fab")
		)
		(fp_line
			(start 0.12065 -0.2794)
			(end -0.12065 -0.2794)
			(stroke
				(width 0.1)
				(type default)
			)
			(layer "B.Fab")
		)
		(fp_line
			(start 0.12065 0.2794)
			(end 0.12065 0.3048)
			(stroke
				(width 0.1)
				(type default)
			)
			(layer "B.Fab")
		)
		(fp_line
			(start 0.12065 0.3048)
			(end 0.67945 0.3048)
			(stroke
				(width 0.1)
				(type default)
			)
			(layer "B.Fab")
		)
		(fp_line
			(start 0.67945 -0.305054)
			(end 0.12065 -0.305054)
			(stroke
				(width 0.1)
				(type default)
			)
			(layer "B.Fab")
		)
		(fp_line
			(start 0.67945 0.3048)
			(end 0.67945 -0.305054)
			(stroke
				(width 0.1)
				(type default)
			)
			(layer "B.Fab")
		)
		(pad "1" smd circle
			(at 0.40005 0 180)
			(size 0 0)
			(layers "B.Cu" "B.Mask" "B.Paste")
			(net "PD_GPP_I_15")
		)
		(pad "2" smd circle
			(at -0.40005 0 180)
			(size 0 0)
			(layers "B.Cu" "B.Mask" "B.Paste")
			(net "GND")
		)
	)
)
